FILE_TYPE = MACRO_DRAWING;
SET COLOR_WIRE YELLOW;
SET COLOR_PROP ORANGE;
SET COLOR_DOT WHITE;
SET COLOR_ARC YELLOW;
SET COLOR_BODY GREEN;
SET COLOR_NOTE PURPLE;
SET PROP_DISPLAY VALUE;
SET PAGE_NUMBER P1;
FORCEADD SYNONYM..1
(1850 2050);
PAINT MONO (1850 2050);
FORCEPROP 2 LAST PATH 4P
J 0
(1850 2150);
DISPLAY 0.872340 (1850 2150);
PAINT YELLOW (1850 2150);
FORCEPROP 1 LAST NEEDS_NO_SIZE TRUE
J 0
(1875 2125);
DISPLAY 0.872340 (1875 2125);
PAINT MONO (1875 2125);
DISPLAY INVISIBLE (1875 2125);
FORCEPROP 1 LAST BODY_TYPE PLUMBING
J 0
(1850 2100);
DISPLAY 0.872340 (1850 2100);
PAINT GREEN (1850 2100);
DISPLAY INVISIBLE (1850 2100);
FORCEPROP 2 LAST CDS_LIB mstr_standard
J 0
(1850 2050);
DISPLAY 0.851064 (1850 2050);
DISPLAY INVISIBLE (1850 2050);
FORCEADD DRAWING..2
(1275 1750);
PAINT MONO (1275 1750);
FORCEPROP 1 LAST LAST_MODIFIED Tue Oct 25 14:26:28 2011
J 0
(1575 1500);
DISPLAY 0.872340 (1575 1500);
PAINT GREEN (1575 1500);
FORCEPROP 1 LAST TITLE P3V3_STBY
J 0
(1325 1700);
DISPLAY 0.872340 (1325 1700);
PAINT GREEN (1325 1700);
FORCEPROP 1 LAST ABBREV P3V3_STBY
J 0
(1325 1650);
DISPLAY 0.872340 (1325 1650);
PAINT GREEN (1325 1650);
WIRE 0 -1 (1900 2050)(2050 2050);
FORCEPROP 2 LAST SIG_NAME P3V3_STBY \G
J 0
(2075 2085);
DISPLAY 0.872340 (2075 2085);
PAINT MONO (2075 2085);
WIRE 16 -1 (1800 2050)(1200 2050);
FORCEPROP 2 LAST SIG_NAME G\I
J 0
(1025 2060);
DISPLAY 0.872340 (1025 2060);
PAINT MONO (1025 2060);
QUIT
